#ISCELL
  pure_quanta quanta_title_block_c *
  *
#ISCELL
  logical_power universal_gnd *
  page58_i18
#ISCELL
  logical_power universal_gnd *
  page58_i2
#ISCELL
  logical_power universal_gnd *
  page58_i25
#ISCELL
  logical_power universal_gnd *
  page58_i35
#ISCELL
  logical_power universal_gnd *
  page58_i39
#ISCELL
  logical_power universal_gnd *
  page58_i40
#ISCELL
  logical_power universal_gnd *
  page58_i46
#ISCELL
  logical_power universal_gnd *
  page58_i47
#ISCELL
  logical_power universal_gnd *
  page58_i48
#ISCELL
  logical_power universal_gnd *
  page58_i49
#ISCELL
  logical_power universal_gnd *
  page58_i5
#ISCELL
  logical_power universal_gnd *
  page58_i50
#ISCELL
  logical_power universal_gnd *
  page58_i51
#ISCELL
  logical_power universal_gnd *
  page58_i52
#ISCELL
  logical_power universal_gnd *
  page58_i53
#ISCELL
  logical_power universal_gnd *
  page58_i54
#CELL
  pure_quanta picoprobe_bxa *
  page58_i55
#CELL
  pure_quanta picoprobe_bxa *
  page58_i57
#CELL
  pure_quanta picoprobe_bxa *
  page58_i58
#CELL
  pure_quanta picoprobe_bxa *
  page58_i59
#CELL
  pure_quanta picoprobe_bxa *
  page58_i60
#CELL
  pure_quanta picoprobe_bxa *
  page58_i61
#CELL
  pure_quanta picoprobe_bxa *
  page58_i62
#CELL
  pure_quanta picoprobe_bxa *
  page58_i63
#CELL
  pure_quanta picoprobe_bxa *
  page58_i64
#CELL
  pure_quanta picoprobe_bxa *
  page58_i65
#CELL
  pure_quanta picoprobe_bxa *
  page58_i66
#CELL
  pure_quanta picoprobe_bxa *
  page58_i67
#CELL
  pure_quanta picoprobe_bxa *
  page58_i68
#CELL
  pure_quanta picoprobe_bxa *
  page58_i69
#CELL
  pure_quanta picoprobe_bxa *
  page58_i70
#CELL
  pure_quanta picoprobe_bxa *
  page58_i71
